(kicad_pcb
	(version 20260206)
	(generator "pcbnew")
	(generator_version "10.0")
	(general
		(thickness 1.6)
		(legacy_teardrops no)
	)
	(paper "A4")
	(title_block
		(title "04192023_DAF0TMB3IC0_F0TG_MB_C_brd_V02_OCP.brd")
		(comment 1 "Grand Teton / footprints 1078-1082 of 8354")
	)
	(layers
		(0 "F.Cu" signal "TOP")
		(4 "In1.Cu" signal "GND")
		(6 "In2.Cu" signal "IN1")
		(8 "In3.Cu" signal "GND1")
		(10 "In4.Cu" signal "IN2")
		(12 "In5.Cu" signal "GND2")
		(14 "In6.Cu" signal "IN3")
		(16 "In7.Cu" signal "GND3")
		(18 "In8.Cu" signal "VCC")
		(20 "In9.Cu" signal "VCC1")
		(22 "In10.Cu" signal "GND4")
		(24 "In11.Cu" signal "IN4")
		(26 "In12.Cu" signal "GND5")
		(28 "In13.Cu" signal "IN5")
		(30 "In14.Cu" signal "GND6")
		(32 "In15.Cu" signal "IN6")
		(34 "In16.Cu" signal "GND7")
		(2 "B.Cu" signal "BOTTOM")
		(9 "F.Adhes" user "F.Adhesive")
		(11 "B.Adhes" user "B.Adhesive")
		(13 "F.Paste" user "Package Geometry/Pastemask Top")
		(15 "B.Paste" user "Package Geometry/Pastemask Bottom")
		(5 "F.SilkS" user "Ref Des/Silkscreen Top")
		(7 "B.SilkS" user "Ref Des/Silkscreen Bottom")
		(1 "F.Mask" user "Board Geometry/Soldermask Top")
		(3 "B.Mask" user "Board Geometry/Soldermask Bottom")
		(17 "Dwgs.User" user "User.Drawings")
		(19 "Cmts.User" user "User.Comments")
		(21 "Eco1.User" user "User.Eco1")
		(23 "Eco2.User" user "User.Eco2")
		(25 "Edge.Cuts" user "Board Geometry/Outline")
		(27 "Margin" user)
		(31 "F.CrtYd" user "Package Geometry/Place Bound Top")
		(29 "B.CrtYd" user "Package Geometry/Place Bound Bottom")
		(35 "F.Fab" user "Ref Des/Assembly Top")
		(33 "B.Fab" user "Ref Des/Assembly Bottom")
	)
	(footprint ""
		(layer "F.Cu")
		(at 221.821502 -70.870318)
		(property "Reference" "PU295"
			(at -1.640332 2.305558 0)
			(unlocked yes)
			(layer "F.SilkS")
			(effects
				(font
					(size 0.7874 0.5842)
					(thickness 0.1524)
				)
				(justify left)
			)
		)
		(property "Value" ""
			(at 0 0 0)
			(layer "F.Fab")
			(effects
				(font
					(size 1.27 1.27)
				)
			)
		)
		(duplicate_pad_numbers_are_jumpers no)
		(fp_line
			(start -1.774952 -1.039876)
			(end -1.774952 1.039876)
			(stroke
				(width 0.1524)
				(type default)
			)
			(layer "F.SilkS")
		)
		(fp_line
			(start -1.774952 1.039876)
			(end 1.774952 1.039876)
			(stroke
				(width 0.1524)
				(type default)
			)
			(layer "F.SilkS")
		)
		(fp_line
			(start 1.774952 -1.039876)
			(end -1.774952 -1.039876)
			(stroke
				(width 0.1524)
				(type default)
			)
			(layer "F.SilkS")
		)
		(fp_line
			(start 1.774952 1.039876)
			(end 1.774952 -1.039876)
			(stroke
				(width 0.1524)
				(type default)
			)
			(layer "F.SilkS")
		)
		(fp_poly
			(pts
				(xy -0.999998 -1.801876) (xy -0.999998 -1.039876) (xy -1.769872 -1.039876) (xy -1.769872 -0.249936)
				(xy -2.531872 -0.249936) (xy -2.531872 -1.801876)
			)
			(stroke
				(width 0)
				(type default)
			)
			(fill yes)
			(layer "F.SilkS")
		)
		(fp_line
			(start -1.769872 -1.039876)
			(end -1.769872 1.039876)
			(stroke
				(width 0.1)
				(type default)
			)
			(layer "F.Fab")
		)
		(fp_line
			(start -1.769872 1.039876)
			(end 1.769872 1.039876)
			(stroke
				(width 0.1)
				(type default)
			)
			(layer "F.Fab")
		)
		(fp_line
			(start 1.769872 -1.039876)
			(end -1.769872 -1.039876)
			(stroke
				(width 0.1)
				(type default)
			)
			(layer "F.Fab")
		)
		(fp_line
			(start 1.769872 1.039876)
			(end 1.769872 -1.039876)
			(stroke
				(width 0.1)
				(type default)
			)
			(layer "F.Fab")
		)
		(fp_poly
			(pts
				(xy -1.769872 -1.039876) (xy -0.999998 -1.039876) (xy -0.999998 -1.801876) (xy -2.531872 -1.801876)
				(xy -2.531872 -0.249936) (xy -1.769872 -0.249936)
			)
			(stroke
				(width 0)
				(type default)
			)
			(fill yes)
			(layer "F.Fab")
		)
		(pad "A1" smd circle
			(at -1.500124 -0.750062)
			(size 0.2286 0.2286)
			(layers "F.Cu" "F.Mask" "F.Paste")
			(net "P3V3_E1S_SENSE_0")
		)
		(pad "A2" smd circle
			(at -0.999998 -0.750062)
			(size 0.2286 0.2286)
			(layers "F.Cu" "F.Mask" "F.Paste")
			(net "P3V3_E1S_VCC_0")
		)
		(pad "A3" smd circle
			(at -0.499872 -0.750062)
			(size 0.2286 0.2286)
			(layers "F.Cu" "F.Mask" "F.Paste")
			(net "P3V3_AUX")
		)
		(pad "A4" smd circle
			(at 0 -0.750062)
			(size 0.2286 0.2286)
			(layers "F.Cu" "F.Mask" "F.Paste")
			(net "P3V3_E1S_0_R")
		)
		(pad "A5" smd circle
			(at 0.499872 -0.750062)
			(size 0.2286 0.2286)
			(layers "F.Cu" "F.Mask" "F.Paste")
			(net "P3V3_AUX")
		)
		(pad "A6" smd circle
			(at 0.999998 -0.750062)
			(size 0.2286 0.2286)
			(layers "F.Cu" "F.Mask" "F.Paste")
			(net "P3V3_E1S_GATE_0")
		)
		(pad "A7" smd circle
			(at 1.500124 -0.750062)
			(size 0.2286 0.2286)
			(layers "F.Cu" "F.Mask" "F.Paste")
			(net "GND")
		)
		(pad "B1" smd circle
			(at -1.500124 -0.249936)
			(size 0.2286 0.2286)
			(layers "F.Cu" "F.Mask" "F.Paste")
			(net "P3V3_E1S_CB_0")
		)
		(pad "B2" smd circle
			(at -0.999998 -0.249936)
			(size 0.2286 0.2286)
			(layers "F.Cu" "F.Mask" "F.Paste")
			(net "GND")
		)
		(pad "B3" smd circle
			(at -0.499872 -0.249936)
			(size 0.2286 0.2286)
			(layers "F.Cu" "F.Mask" "F.Paste")
			(net "P3V3_AUX")
		)
		(pad "B4" smd circle
			(at 0 -0.249936)
			(size 0.2286 0.2286)
			(layers "F.Cu" "F.Mask" "F.Paste")
			(net "P3V3_E1S_0_R")
		)
		(pad "B5" smd circle
			(at 0.499872 -0.249936)
			(size 0.2286 0.2286)
			(layers "F.Cu" "F.Mask" "F.Paste")
			(net "P3V3_AUX")
		)
		(pad "B6" smd circle
			(at 0.999998 -0.249936)
			(size 0.2286 0.2286)
			(layers "F.Cu" "F.Mask" "F.Paste")
			(net "P3V3_E1S_0_R")
		)
		(pad "B7" smd circle
			(at 1.500124 -0.249936)
			(size 0.2286 0.2286)
			(layers "F.Cu" "F.Mask" "F.Paste")
			(net "GND")
		)
		(pad "C1" smd circle
			(at -1.500124 0.249936)
			(size 0.2286 0.2286)
			(layers "F.Cu" "F.Mask" "F.Paste")
			(net "GND")
		)
		(pad "C2" smd circle
			(at -0.999998 0.249936)
			(size 0.2286 0.2286)
			(layers "F.Cu" "F.Mask" "F.Paste")
			(net "GND")
		)
		(pad "C3" smd circle
			(at -0.499872 0.249936)
			(size 0.2286 0.2286)
			(layers "F.Cu" "F.Mask" "F.Paste")
			(net "P3V3_AUX")
		)
		(pad "C4" smd circle
			(at 0 0.249936)
			(size 0.2286 0.2286)
			(layers "F.Cu" "F.Mask" "F.Paste")
			(net "P3V3_E1S_0_R")
		)
		(pad "C5" smd circle
			(at 0.499872 0.249936)
			(size 0.2286 0.2286)
			(layers "F.Cu" "F.Mask" "F.Paste")
			(net "P3V3_AUX")
		)
		(pad "C6" smd circle
			(at 0.999998 0.249936)
			(size 0.2286 0.2286)
			(layers "F.Cu" "F.Mask" "F.Paste")
			(net "P3V3_E1S_0_R")
		)
		(pad "C7" smd circle
			(at 1.500124 0.249936)
			(size 0.2286 0.2286)
			(layers "F.Cu" "F.Mask" "F.Paste")
			(net "P3V3_E1S_FAULT_0")
		)
		(pad "D1" smd circle
			(at -1.500124 0.750062)
			(size 0.2286 0.2286)
			(layers "F.Cu" "F.Mask" "F.Paste")
			(net "P3V3_E1S_REG_0")
		)
		(pad "D2" smd circle
			(at -0.999998 0.750062)
			(size 0.2286 0.2286)
			(layers "F.Cu" "F.Mask" "F.Paste")
			(net "P3V3_E1S_UV_0")
		)
		(pad "D3" smd circle
			(at -0.499872 0.750062)
			(size 0.2286 0.2286)
			(layers "F.Cu" "F.Mask" "F.Paste")
			(net "P3V3_E1S_OV_0")
		)
		(pad "D4" smd circle
			(at 0 0.750062)
			(size 0.2286 0.2286)
			(layers "F.Cu" "F.Mask" "F.Paste")
			(net "P3V3_E1S_0_R")
		)
		(pad "D5" smd circle
			(at 0.499872 0.750062)
			(size 0.2286 0.2286)
			(layers "F.Cu" "F.Mask" "F.Paste")
			(net "P3V3_AUX")
		)
		(pad "D6" smd circle
			(at 0.999998 0.750062)
			(size 0.2286 0.2286)
			(layers "F.Cu" "F.Mask" "F.Paste")
			(net "P3V3_E1S_0_R")
		)
		(pad "D7" smd circle
			(at 1.500124 0.750062)
			(size 0.2286 0.2286)
			(layers "F.Cu" "F.Mask" "F.Paste")
			(net "P3V3_E1S_PWRGD_0")
		)
	)
	(footprint ""
		(layer "F.Cu")
		(at 279.513792 -116.67617 180)
		(property "Reference" "R2968"
			(at 0 0 180)
			(layer "F.SilkS")
			(hide yes)
			(effects
				(font
					(size 1.27 1.27)
				)
			)
		)
		(property "Value" ""
			(at 0 0 180)
			(layer "F.Fab")
			(effects
				(font
					(size 1.27 1.27)
				)
			)
		)
		(duplicate_pad_numbers_are_jumpers no)
		(fp_line
			(start 0.7874 0.4064)
			(end -0.7874 0.4064)
			(stroke
				(width 0.1524)
				(type default)
			)
			(layer "F.SilkS")
		)
		(fp_line
			(start 0.7874 -0.4064)
			(end 0.7874 0.4064)
			(stroke
				(width 0.1524)
				(type default)
			)
			(layer "F.SilkS")
		)
		(fp_line
			(start -0.7874 0.4064)
			(end -0.7874 -0.4064)
			(stroke
				(width 0.1524)
				(type default)
			)
			(layer "F.SilkS")
		)
		(fp_line
			(start -0.7874 -0.4064)
			(end 0.7874 -0.4064)
			(stroke
				(width 0.1524)
				(type default)
			)
			(layer "F.SilkS")
		)
		(fp_line
			(start 0.67945 0.3048)
			(end 0.120396 0.3048)
			(stroke
				(width 0.1)
				(type default)
			)
			(layer "F.Fab")
		)
		(fp_line
			(start 0.67945 -0.3048)
			(end 0.67945 0.3048)
			(stroke
				(width 0.1)
				(type default)
			)
			(layer "F.Fab")
		)
		(fp_line
			(start 0.12065 -0.2794)
			(end 0.12065 -0.3048)
			(stroke
				(width 0.1)
				(type default)
			)
			(layer "F.Fab")
		)
		(fp_line
			(start 0.12065 -0.3048)
			(end 0.67945 -0.3048)
			(stroke
				(width 0.1)
				(type default)
			)
			(layer "F.Fab")
		)
		(fp_line
			(start 0.120396 0.3048)
			(end 0.120396 0.2794)
			(stroke
				(width 0.1)
				(type default)
			)
			(layer "F.Fab")
		)
		(fp_line
			(start 0.120396 0.2794)
			(end -0.12065 0.2794)
			(stroke
				(width 0.1)
				(type default)
			)
			(layer "F.Fab")
		)
		(fp_line
			(start -0.12065 0.3048)
			(end -0.67945 0.3048)
			(stroke
				(width 0.1)
				(type default)
			)
			(layer "F.Fab")
		)
		(fp_line
			(start -0.12065 0.2794)
			(end -0.12065 0.3048)
			(stroke
				(width 0.1)
				(type default)
			)
			(layer "F.Fab")
		)
		(fp_line
			(start -0.12065 -0.2794)
			(end 0.12065 -0.2794)
			(stroke
				(width 0.1)
				(type default)
			)
			(layer "F.Fab")
		)
		(fp_line
			(start -0.12065 -0.305054)
			(end -0.12065 -0.2794)
			(stroke
				(width 0.1)
				(type default)
			)
			(layer "F.Fab")
		)
		(fp_line
			(start -0.67945 0.3048)
			(end -0.67945 -0.305054)
			(stroke
				(width 0.1)
				(type default)
			)
			(layer "F.Fab")
		)
		(fp_line
			(start -0.67945 -0.305054)
			(end -0.12065 -0.305054)
			(stroke
				(width 0.1)
				(type default)
			)
			(layer "F.Fab")
		)
		(pad "1" smd circle
			(at -0.40005 0 180)
			(size 0 0)
			(layers "F.Cu" "F.Mask" "F.Paste")
			(net "SMB_PCIE0_3V3AUX_SDA_R3")
		)
		(pad "2" smd circle
			(at 0.40005 0 180)
			(size 0 0)
			(layers "F.Cu" "F.Mask" "F.Paste")
			(net "SMB_SENSOR_M2_P1_3V3AUX_SDA")
		)
	)
	(footprint ""
		(layer "F.Cu")
		(at 413.766 -100.203 90)
		(property "Reference" "R8093"
			(at 0 0 90)
			(layer "F.SilkS")
			(hide yes)
			(effects
				(font
					(size 1.27 1.27)
				)
			)
		)
		(property "Value" ""
			(at 0 0 90)
			(layer "F.Fab")
			(effects
				(font
					(size 1.27 1.27)
				)
			)
		)
		(duplicate_pad_numbers_are_jumpers no)
		(fp_line
			(start 0.7874 -0.4064)
			(end 0.7874 0.4064)
			(stroke
				(width 0.1524)
				(type default)
			)
			(layer "F.SilkS")
		)
		(fp_line
			(start -0.7874 -0.4064)
			(end 0.7874 -0.4064)
			(stroke
				(width 0.1524)
				(type default)
			)
			(layer "F.SilkS")
		)
		(fp_line
			(start 0.7874 0.4064)
			(end -0.7874 0.4064)
			(stroke
				(width 0.1524)
				(type default)
			)
			(layer "F.SilkS")
		)
		(fp_line
			(start -0.7874 0.4064)
			(end -0.7874 -0.4064)
			(stroke
				(width 0.1524)
				(type default)
			)
			(layer "F.SilkS")
		)
		(fp_line
			(start -0.12065 -0.305054)
			(end -0.12065 -0.2794)
			(stroke
				(width 0.1)
				(type default)
			)
			(layer "F.Fab")
		)
		(fp_line
			(start -0.67945 -0.305054)
			(end -0.12065 -0.305054)
			(stroke
				(width 0.1)
				(type default)
			)
			(layer "F.Fab")
		)
		(fp_line
			(start 0.67945 -0.3048)
			(end 0.67945 0.3048)
			(stroke
				(width 0.1)
				(type default)
			)
			(layer "F.Fab")
		)
		(fp_line
			(start 0.12065 -0.3048)
			(end 0.67945 -0.3048)
			(stroke
				(width 0.1)
				(type default)
			)
			(layer "F.Fab")
		)
		(fp_line
			(start 0.12065 -0.2794)
			(end 0.12065 -0.3048)
			(stroke
				(width 0.1)
				(type default)
			)
			(layer "F.Fab")
		)
		(fp_line
			(start -0.12065 -0.2794)
			(end 0.12065 -0.2794)
			(stroke
				(width 0.1)
				(type default)
			)
			(layer "F.Fab")
		)
		(fp_line
			(start 0.120396 0.2794)
			(end -0.12065 0.2794)
			(stroke
				(width 0.1)
				(type default)
			)
			(layer "F.Fab")
		)
		(fp_line
			(start -0.12065 0.2794)
			(end -0.12065 0.3048)
			(stroke
				(width 0.1)
				(type default)
			)
			(layer "F.Fab")
		)
		(fp_line
			(start 0.67945 0.3048)
			(end 0.120396 0.3048)
			(stroke
				(width 0.1)
				(type default)
			)
			(layer "F.Fab")
		)
		(fp_line
			(start 0.120396 0.3048)
			(end 0.120396 0.2794)
			(stroke
				(width 0.1)
				(type default)
			)
			(layer "F.Fab")
		)
		(fp_line
			(start -0.12065 0.3048)
			(end -0.67945 0.3048)
			(stroke
				(width 0.1)
				(type default)
			)
			(layer "F.Fab")
		)
		(fp_line
			(start -0.67945 0.3048)
			(end -0.67945 -0.305054)
			(stroke
				(width 0.1)
				(type default)
			)
			(layer "F.Fab")
		)
		(pad "1" smd circle
			(at -0.40005 0 90)
			(size 0 0)
			(layers "F.Cu" "F.Mask" "F.Paste")
			(net "OCP_V3_1_P3V3_R1_PWRGD")
		)
		(pad "2" smd circle
			(at 0.40005 0 90)
			(size 0 0)
			(layers "F.Cu" "F.Mask" "F.Paste")
			(net "GND")
		)
	)
	(footprint ""
		(layer "F.Cu")
		(at 75.265534 -172.414184)
		(property "Reference" "PR202"
			(at 0 0 0)
			(layer "F.SilkS")
			(hide yes)
			(effects
				(font
					(size 1.27 1.27)
				)
			)
		)
		(property "Value" ""
			(at 0 0 0)
			(layer "F.Fab")
			(effects
				(font
					(size 1.27 1.27)
				)
			)
		)
		(duplicate_pad_numbers_are_jumpers no)
		(fp_line
			(start -0.7874 -0.4064)
			(end 0.7874 -0.4064)
			(stroke
				(width 0.1524)
				(type default)
			)
			(layer "F.SilkS")
		)
		(fp_line
			(start -0.7874 0.4064)
			(end -0.7874 -0.4064)
			(stroke
				(width 0.1524)
				(type default)
			)
			(layer "F.SilkS")
		)
		(fp_line
			(start 0.7874 -0.4064)
			(end 0.7874 0.4064)
			(stroke
				(width 0.1524)
				(type default)
			)
			(layer "F.SilkS")
		)
		(fp_line
			(start 0.7874 0.4064)
			(end -0.7874 0.4064)
			(stroke
				(width 0.1524)
				(type default)
			)
			(layer "F.SilkS")
		)
		(fp_line
			(start -0.67945 -0.305054)
			(end -0.12065 -0.305054)
			(stroke
				(width 0.1)
				(type default)
			)
			(layer "F.Fab")
		)
		(fp_line
			(start -0.67945 0.3048)
			(end -0.67945 -0.305054)
			(stroke
				(width 0.1)
				(type default)
			)
			(layer "F.Fab")
		)
		(fp_line
			(start -0.12065 -0.305054)
			(end -0.12065 -0.2794)
			(stroke
				(width 0.1)
				(type default)
			)
			(layer "F.Fab")
		)
		(fp_line
			(start -0.12065 -0.2794)
			(end 0.12065 -0.2794)
			(stroke
				(width 0.1)
				(type default)
			)
			(layer "F.Fab")
		)
		(fp_line
			(start -0.12065 0.2794)
			(end -0.12065 0.3048)
			(stroke
				(width 0.1)
				(type default)
			)
			(layer "F.Fab")
		)
		(fp_line
			(start -0.12065 0.3048)
			(end -0.67945 0.3048)
			(stroke
				(width 0.1)
				(type default)
			)
			(layer "F.Fab")
		)
		(fp_line
			(start 0.120396 0.2794)
			(end -0.12065 0.2794)
			(stroke
				(width 0.1)
				(type default)
			)
			(layer "F.Fab")
		)
		(fp_line
			(start 0.120396 0.3048)
			(end 0.120396 0.2794)
			(stroke
				(width 0.1)
				(type default)
			)
			(layer "F.Fab")
		)
		(fp_line
			(start 0.12065 -0.3048)
			(end 0.67945 -0.3048)
			(stroke
				(width 0.1)
				(type default)
			)
			(layer "F.Fab")
		)
		(fp_line
			(start 0.12065 -0.2794)
			(end 0.12065 -0.3048)
			(stroke
				(width 0.1)
				(type default)
			)
			(layer "F.Fab")
		)
		(fp_line
			(start 0.67945 -0.3048)
			(end 0.67945 0.3048)
			(stroke
				(width 0.1)
				(type default)
			)
			(layer "F.Fab")
		)
		(fp_line
			(start 0.67945 0.3048)
			(end 0.120396 0.3048)
			(stroke
				(width 0.1)
				(type default)
			)
			(layer "F.Fab")
		)
		(pad "1" smd circle
			(at -0.40005 0)
			(size 0 0)
			(layers "F.Cu" "F.Mask" "F.Paste")
			(net "GND")
		)
		(pad "2" smd circle
			(at 0.40005 0)
			(size 0 0)
			(layers "F.Cu" "F.Mask" "F.Paste")
			(net "PVDDCR_CPU0_P1_LSET5")
		)
	)
	(footprint ""
		(layer "F.Cu")
		(at 278.006556 -436.223664 -90)
		(property "Reference" "C70"
			(at 0 0 270)
			(layer "F.SilkS")
			(hide yes)
			(effects
				(font
					(size 1.27 1.27)
				)
			)
		)
		(property "Value" ""
			(at 0 0 270)
			(layer "F.Fab")
			(effects
				(font
					(size 1.27 1.27)
				)
			)
		)
		(duplicate_pad_numbers_are_jumpers no)
		(fp_line
			(start -0.7874 0.4064)
			(end -0.7874 -0.4064)
			(stroke
				(width 0.1524)
				(type default)
			)
			(layer "F.SilkS")
		)
		(fp_line
			(start 0.7874 0.4064)
			(end -0.7874 0.4064)
			(stroke
				(width 0.1524)
				(type default)
			)
			(layer "F.SilkS")
		)
		(fp_line
			(start -0.7874 -0.4064)
			(end 0.7874 -0.4064)
			(stroke
				(width 0.1524)
				(type default)
			)
			(layer "F.SilkS")
		)
		(fp_line
			(start 0.7874 -0.4064)
			(end 0.7874 0.4064)
			(stroke
				(width 0.1524)
				(type default)
			)
			(layer "F.SilkS")
		)
		(fp_line
			(start -0.67945 0.3048)
			(end -0.67945 -0.305054)
			(stroke
				(width 0.1)
				(type default)
			)
			(layer "F.Fab")
		)
		(fp_line
			(start -0.12065 0.3048)
			(end -0.67945 0.3048)
			(stroke
				(width 0.1)
				(type default)
			)
			(layer "F.Fab")
		)
		(fp_line
			(start 0.120396 0.3048)
			(end 0.120396 0.2794)
			(stroke
				(width 0.1)
				(type default)
			)
			(layer "F.Fab")
		)
		(fp_line
			(start 0.67945 0.3048)
			(end 0.120396 0.3048)
			(stroke
				(width 0.1)
				(type default)
			)
			(layer "F.Fab")
		)
		(fp_line
			(start -0.12065 0.2794)
			(end -0.12065 0.3048)
			(stroke
				(width 0.1)
				(type default)
			)
			(layer "F.Fab")
		)
		(fp_line
			(start 0.120396 0.2794)
			(end -0.12065 0.2794)
			(stroke
				(width 0.1)
				(type default)
			)
			(layer "F.Fab")
		)
		(fp_line
			(start -0.12065 -0.2794)
			(end 0.12065 -0.2794)
			(stroke
				(width 0.1)
				(type default)
			)
			(layer "F.Fab")
		)
		(fp_line
			(start 0.12065 -0.2794)
			(end 0.12065 -0.3048)
			(stroke
				(width 0.1)
				(type default)
			)
			(layer "F.Fab")
		)
		(fp_line
			(start 0.12065 -0.3048)
			(end 0.67945 -0.3048)
			(stroke
				(width 0.1)
				(type default)
			)
			(layer "F.Fab")
		)
		(fp_line
			(start 0.67945 -0.3048)
			(end 0.67945 0.3048)
			(stroke
				(width 0.1)
				(type default)
			)
			(layer "F.Fab")
		)
		(fp_line
			(start -0.67945 -0.305054)
			(end -0.12065 -0.305054)
			(stroke
				(width 0.1)
				(type default)
			)
			(layer "F.Fab")
		)
		(fp_line
			(start -0.12065 -0.305054)
			(end -0.12065 -0.2794)
			(stroke
				(width 0.1)
				(type default)
			)
			(layer "F.Fab")
		)
		(pad "1" smd circle
			(at -0.40005 0 270)
			(size 0 0)
			(layers "F.Cu" "F.Mask" "F.Paste")
			(net "HPDB_HSC_PWRGD_ISO")
		)
		(pad "2" smd circle
			(at 0.40005 0 270)
			(size 0 0)
			(layers "F.Cu" "F.Mask" "F.Paste")
			(net "GND")
		)
	)
)
